(kicad_pcb
	(version 20260206)
	(generator "pcbnew")
	(generator_version "10.0")
	(general
		(thickness 1.6)
		(legacy_teardrops no)
	)
	(paper "A4")
	(title_block
		(title "baseboard — 13948-1b.1110WZS1818.brd")
		(comment 1 "Honey Badger (Wiwynn) / footprints 2409-2415 of 2523")
	)
	(layers
		(0 "F.Cu" signal "TOP")
		(4 "In1.Cu" signal "L2GND")
		(6 "In2.Cu" signal "L3")
		(8 "In3.Cu" signal "L4VCC")
		(10 "In4.Cu" signal "L5VCC")
		(12 "In5.Cu" signal "L6")
		(14 "In6.Cu" signal "L7GND")
		(2 "B.Cu" signal "BOTTOM")
		(9 "F.Adhes" user "F.Adhesive")
		(11 "B.Adhes" user "B.Adhesive")
		(13 "F.Paste" user "Package Geometry/Pastemask Top")
		(15 "B.Paste" user "Package Geometry/Pastemask Bottom")
		(5 "F.SilkS" user "Ref Des/Silkscreen Top")
		(7 "B.SilkS" user "Ref Des/Silkscreen Bottom")
		(1 "F.Mask" user "Board Geometry/Soldermask Top")
		(3 "B.Mask" user "Board Geometry/Soldermask Bottom")
		(17 "Dwgs.User" user "User.Drawings")
		(19 "Cmts.User" user "User.Comments")
		(21 "Eco1.User" user "User.Eco1")
		(23 "Eco2.User" user "User.Eco2")
		(25 "Edge.Cuts" user "Board Geometry/Outline")
		(27 "Margin" user)
		(31 "F.CrtYd" user "Package Geometry/Place Bound Top")
		(29 "B.CrtYd" user "Package Geometry/Place Bound Bottom")
		(35 "F.Fab" user "Ref Des/Assembly Top")
		(33 "B.Fab" user "Ref Des/Assembly Bottom")
	)
	(footprint ""
		(layer "B.Cu")
		(at 310.896 -184.658 90)
		(property "Reference" "R313"
			(at 0 0 90)
			(layer "B.SilkS")
			(hide yes)
			(effects
				(font
					(size 1.27 1.27)
				)
				(justify mirror)
			)
		)
		(property "Value" "0R2J-2-GP"
			(at -0.064008 -3.993896 90)
			(unlocked yes)
			(layer "B.Fab")
			(hide yes)
			(effects
				(font
					(size 1.016 1.016)
					(thickness 0.1524)
				)
				(justify mirror)
			)
		)
		(property "Device Type" "R402H16"
			(at -0.064008 -5.517896 90)
			(unlocked yes)
			(layer "B.Fab")
			(hide yes)
			(effects
				(font
					(size 1.016 1.016)
					(thickness 0.1524)
				)
				(justify mirror)
			)
		)
		(duplicate_pad_numbers_are_jumpers no)
		(fp_line
			(start 0.508 -0.9398)
			(end 0.508 0.9398)
			(stroke
				(width 0.1524)
				(type default)
			)
			(layer "B.SilkS")
		)
		(fp_line
			(start -0.508 -0.9398)
			(end 0.508 -0.9398)
			(stroke
				(width 0.1524)
				(type default)
			)
			(layer "B.SilkS")
		)
		(fp_rect
			(start 0.508 0.9398)
			(end -0.508 -0.9398)
			(stroke
				(width 0)
				(type default)
			)
			(fill no)
			(layer "B.CrtYd")
		)
		(fp_rect
			(start 0.508 0.9398)
			(end -0.508 -0.9398)
			(stroke
				(width 0)
				(type default)
			)
			(fill no)
			(layer "B.Fab")
		)
		(pad "1" smd custom
			(at 0 -0.4445 270)
			(size 0.1397 0.1397)
			(layers "B.Cu" "B.Mask" "B.Paste")
			(net "BMC0_I2C_IO_EXP_RESET#")
			(options
				(clearance outline)
				(anchor circle)
			)
			(primitives
				(gr_poly
					(pts
						(arc
							(start -0.1778 0.2794)
							(mid -0.249642 0.249642)
							(end -0.2794 0.1778)
						)
						(arc
							(start -0.2794 -0.1778)
							(mid -0.249642 -0.249642)
							(end -0.1778 -0.2794)
						)
						(arc
							(start 0.1778 -0.2794)
							(mid 0.249642 -0.249642)
							(end 0.2794 -0.1778)
						)
						(arc
							(start 0.2794 0.1778)
							(mid 0.249642 0.249642)
							(end 0.1778 0.2794)
						)
					)
					(width 0)
					(fill yes)
				)
			)
		)
		(pad "2" smd custom
			(at 0 0.4445 270)
			(size 0.1397 0.1397)
			(layers "B.Cu" "B.Mask" "B.Paste")
			(net "I2C_IO_EXP_RESET#")
			(options
				(clearance outline)
				(anchor circle)
			)
			(primitives
				(gr_poly
					(pts
						(arc
							(start -0.1778 0.2794)
							(mid -0.249642 0.249642)
							(end -0.2794 0.1778)
						)
						(arc
							(start -0.2794 -0.1778)
							(mid -0.249642 -0.249642)
							(end -0.1778 -0.2794)
						)
						(arc
							(start 0.1778 -0.2794)
							(mid 0.249642 -0.249642)
							(end 0.2794 -0.1778)
						)
						(arc
							(start 0.2794 0.1778)
							(mid 0.249642 0.249642)
							(end 0.1778 0.2794)
						)
					)
					(width 0)
					(fill yes)
				)
			)
		)
	)
	(footprint ""
		(layer "B.Cu")
		(at 11.05408 -231.822752)
		(property "Reference" "R512"
			(at 0 0 0)
			(layer "B.SilkS")
			(hide yes)
			(effects
				(font
					(size 1.27 1.27)
				)
				(justify mirror)
			)
		)
		(property "Value" "0R2J-2-GP"
			(at -0.064008 -3.993896 0)
			(unlocked yes)
			(layer "B.Fab")
			(hide yes)
			(effects
				(font
					(size 1.016 1.016)
					(thickness 0.1524)
				)
				(justify mirror)
			)
		)
		(property "Device Type" "R402H16"
			(at -0.064008 -5.517896 0)
			(unlocked yes)
			(layer "B.Fab")
			(hide yes)
			(effects
				(font
					(size 1.016 1.016)
					(thickness 0.1524)
				)
				(justify mirror)
			)
		)
		(duplicate_pad_numbers_are_jumpers no)
		(fp_line
			(start -0.508 -0.9398)
			(end 0.508 -0.9398)
			(stroke
				(width 0.1524)
				(type default)
			)
			(layer "B.SilkS")
		)
		(fp_line
			(start 0.508 -0.9398)
			(end 0.508 0.9398)
			(stroke
				(width 0.1524)
				(type default)
			)
			(layer "B.SilkS")
		)
		(fp_rect
			(start 0.508 0.9398)
			(end -0.508 -0.9398)
			(stroke
				(width 0)
				(type default)
			)
			(fill no)
			(layer "B.CrtYd")
		)
		(fp_rect
			(start 0.508 0.9398)
			(end -0.508 -0.9398)
			(stroke
				(width 0)
				(type default)
			)
			(fill no)
			(layer "B.Fab")
		)
		(pad "1" smd custom
			(at 0 -0.4445 180)
			(size 0.1397 0.1397)
			(layers "B.Cu" "B.Mask" "B.Paste")
			(net "SAS_HDD_PWR10_PCIE")
			(options
				(clearance outline)
				(anchor circle)
			)
			(primitives
				(gr_poly
					(pts
						(arc
							(start -0.1778 0.2794)
							(mid -0.249642 0.249642)
							(end -0.2794 0.1778)
						)
						(arc
							(start -0.2794 -0.1778)
							(mid -0.249642 -0.249642)
							(end -0.1778 -0.2794)
						)
						(arc
							(start 0.1778 -0.2794)
							(mid 0.249642 -0.249642)
							(end 0.2794 -0.1778)
						)
						(arc
							(start 0.2794 0.1778)
							(mid 0.249642 0.249642)
							(end 0.1778 0.2794)
						)
					)
					(width 0)
					(fill yes)
				)
			)
		)
		(pad "2" smd custom
			(at 0 0.4445 180)
			(size 0.1397 0.1397)
			(layers "B.Cu" "B.Mask" "B.Paste")
			(net "SAS_HDD_PWR10")
			(options
				(clearance outline)
				(anchor circle)
			)
			(primitives
				(gr_poly
					(pts
						(arc
							(start -0.1778 0.2794)
							(mid -0.249642 0.249642)
							(end -0.2794 0.1778)
						)
						(arc
							(start -0.2794 -0.1778)
							(mid -0.249642 -0.249642)
							(end -0.1778 -0.2794)
						)
						(arc
							(start 0.1778 -0.2794)
							(mid 0.249642 -0.249642)
							(end 0.2794 -0.1778)
						)
						(arc
							(start 0.2794 0.1778)
							(mid 0.249642 0.249642)
							(end 0.1778 0.2794)
						)
					)
					(width 0)
					(fill yes)
				)
			)
		)
	)
	(footprint ""
		(layer "B.Cu")
		(at 118.688612 -221.996)
		(property "Reference" "SR885"
			(at 0 0 0)
			(layer "B.SilkS")
			(hide yes)
			(effects
				(font
					(size 1.27 1.27)
				)
				(justify mirror)
			)
		)
		(property "Value" "0R2J-2-GP"
			(at -0.064008 -3.993896 0)
			(unlocked yes)
			(layer "B.Fab")
			(hide yes)
			(effects
				(font
					(size 1.016 1.016)
					(thickness 0.1524)
				)
				(justify mirror)
			)
		)
		(property "Device Type" "R402H16"
			(at -0.064008 -5.517896 0)
			(unlocked yes)
			(layer "B.Fab")
			(hide yes)
			(effects
				(font
					(size 1.016 1.016)
					(thickness 0.1524)
				)
				(justify mirror)
			)
		)
		(duplicate_pad_numbers_are_jumpers no)
		(fp_line
			(start -0.508 -0.9398)
			(end 0.508 -0.9398)
			(stroke
				(width 0.1524)
				(type default)
			)
			(layer "B.SilkS")
		)
		(fp_line
			(start 0.508 -0.9398)
			(end 0.508 0.9398)
			(stroke
				(width 0.1524)
				(type default)
			)
			(layer "B.SilkS")
		)
		(fp_rect
			(start 0.508 0.9398)
			(end -0.508 -0.9398)
			(stroke
				(width 0)
				(type default)
			)
			(fill no)
			(layer "B.CrtYd")
		)
		(fp_rect
			(start 0.508 0.9398)
			(end -0.508 -0.9398)
			(stroke
				(width 0)
				(type default)
			)
			(fill no)
			(layer "B.Fab")
		)
		(pad "1" smd custom
			(at 0 -0.4445 180)
			(size 0.1397 0.1397)
			(layers "B.Cu" "B.Mask" "B.Paste")
			(net "SAS_GF_EXP_RX_DP7")
			(options
				(clearance outline)
				(anchor circle)
			)
			(primitives
				(gr_poly
					(pts
						(arc
							(start -0.1778 0.2794)
							(mid -0.249642 0.249642)
							(end -0.2794 0.1778)
						)
						(arc
							(start -0.2794 -0.1778)
							(mid -0.249642 -0.249642)
							(end -0.1778 -0.2794)
						)
						(arc
							(start 0.1778 -0.2794)
							(mid 0.249642 -0.249642)
							(end 0.2794 -0.1778)
						)
						(arc
							(start 0.2794 0.1778)
							(mid 0.249642 0.249642)
							(end 0.1778 0.2794)
						)
					)
					(width 0)
					(fill yes)
				)
			)
		)
		(pad "2" smd custom
			(at 0 0.4445 180)
			(size 0.1397 0.1397)
			(layers "B.Cu" "B.Mask" "B.Paste")
			(net "SAS_HDD_CONN_SER_RX7_P")
			(options
				(clearance outline)
				(anchor circle)
			)
			(primitives
				(gr_poly
					(pts
						(arc
							(start -0.1778 0.2794)
							(mid -0.249642 0.249642)
							(end -0.2794 0.1778)
						)
						(arc
							(start -0.2794 -0.1778)
							(mid -0.249642 -0.249642)
							(end -0.1778 -0.2794)
						)
						(arc
							(start 0.1778 -0.2794)
							(mid 0.249642 -0.249642)
							(end 0.2794 -0.1778)
						)
						(arc
							(start 0.2794 0.1778)
							(mid 0.249642 0.249642)
							(end 0.1778 0.2794)
						)
					)
					(width 0)
					(fill yes)
				)
			)
		)
	)
	(footprint ""
		(layer "B.Cu")
		(at 95.51416 -31.623)
		(property "Reference" "SC864"
			(at 0 0 0)
			(layer "B.SilkS")
			(hide yes)
			(effects
				(font
					(size 1.27 1.27)
				)
				(justify mirror)
			)
		)
		(property "Value" "SCD22U6D3V1MX-1-GP"
			(at 2.8321 -1.7399 0)
			(unlocked yes)
			(layer "B.Fab")
			(hide yes)
			(effects
				(font
					(size 1.016 1.016)
					(thickness 0.1524)
				)
				(justify mirror)
			)
		)
		(property "Device Type" "C0201H13"
			(at 2.8321 -3.2639 0)
			(unlocked yes)
			(layer "B.Fab")
			(hide yes)
			(effects
				(font
					(size 1.016 1.016)
					(thickness 0.1524)
				)
				(justify mirror)
			)
		)
		(duplicate_pad_numbers_are_jumpers no)
		(fp_rect
			(start 0.2794 0.6477)
			(end -0.2794 -0.6477)
			(stroke
				(width 0)
				(type default)
			)
			(fill no)
			(layer "B.CrtYd")
		)
		(fp_rect
			(start 0.2794 0.6477)
			(end -0.2794 -0.6477)
			(stroke
				(width 0)
				(type default)
			)
			(fill no)
			(layer "B.Fab")
		)
		(pad "1" smd custom
			(at 0 -0.2794 180)
			(size 0.0762 0.0762)
			(layers "B.Cu" "B.Mask" "B.Paste")
			(net "PCIE_SAS_C_CPU_RX_N1")
			(options
				(clearance outline)
				(anchor circle)
			)
			(primitives
				(gr_poly
					(pts
						(arc
							(start 0.1524 0.127)
							(mid 0.137521 0.162921)
							(end 0.1016 0.1778)
						)
						(arc
							(start -0.1016 0.1778)
							(mid -0.137521 0.162921)
							(end -0.1524 0.127)
						)
						(arc
							(start -0.1524 -0.127)
							(mid -0.137521 -0.162921)
							(end -0.1016 -0.1778)
						)
						(arc
							(start 0.1016 -0.1778)
							(mid 0.137521 -0.162921)
							(end 0.1524 -0.127)
						)
					)
					(width 0)
					(fill yes)
				)
			)
		)
		(pad "2" smd custom
			(at 0 0.2794 180)
			(size 0.0762 0.0762)
			(layers "B.Cu" "B.Mask" "B.Paste")
			(net "PCIE_SAS_CPU_RX_N1")
			(options
				(clearance outline)
				(anchor circle)
			)
			(primitives
				(gr_poly
					(pts
						(arc
							(start 0.1524 0.127)
							(mid 0.137521 0.162921)
							(end 0.1016 0.1778)
						)
						(arc
							(start -0.1016 0.1778)
							(mid -0.137521 0.162921)
							(end -0.1524 0.127)
						)
						(arc
							(start -0.1524 -0.127)
							(mid -0.137521 -0.162921)
							(end -0.1016 -0.1778)
						)
						(arc
							(start 0.1016 -0.1778)
							(mid 0.137521 -0.162921)
							(end 0.1524 -0.127)
						)
					)
					(width 0)
					(fill yes)
				)
			)
		)
	)
	(footprint ""
		(layer "B.Cu")
		(at 103.64597 -86.0679 -90)
		(property "Reference" "SC1211"
			(at 0 0 90)
			(layer "B.SilkS")
			(hide yes)
			(effects
				(font
					(size 1.27 1.27)
				)
				(justify mirror)
			)
		)
		(property "Value" "SC1KP50V2KX-1GP"
			(at -1.1811 -2.7051 270)
			(unlocked yes)
			(layer "B.Fab")
			(hide yes)
			(effects
				(font
					(size 1.016 1.016)
					(thickness 0.1524)
				)
				(justify mirror)
			)
		)
		(property "Device Type" "C402H22"
			(at -1.1811 -4.2291 270)
			(unlocked yes)
			(layer "B.Fab")
			(hide yes)
			(effects
				(font
					(size 1.016 1.016)
					(thickness 0.1524)
				)
				(justify mirror)
			)
		)
		(duplicate_pad_numbers_are_jumpers no)
		(fp_rect
			(start 0.4318 0.9525)
			(end -0.4318 -0.9525)
			(stroke
				(width 0)
				(type default)
			)
			(fill no)
			(layer "B.CrtYd")
		)
		(fp_rect
			(start 0.4318 0.9525)
			(end -0.4318 -0.9525)
			(stroke
				(width 0)
				(type default)
			)
			(fill no)
			(layer "B.Fab")
		)
		(pad "1" smd custom
			(at 0 -0.4445 90)
			(size 0.1524 0.1524)
			(layers "B.Cu" "B.Mask" "B.Paste")
			(net "P1V8_E")
			(options
				(clearance outline)
				(anchor circle)
			)
			(primitives
				(gr_poly
					(pts
						(arc
							(start 0.3048 0.2032)
							(mid 0.275042 0.275042)
							(end 0.2032 0.3048)
						)
						(arc
							(start -0.2032 0.3048)
							(mid -0.275042 0.275042)
							(end -0.3048 0.2032)
						)
						(arc
							(start -0.3048 -0.2032)
							(mid -0.275042 -0.275042)
							(end -0.2032 -0.3048)
						)
						(arc
							(start 0.2032 -0.3048)
							(mid 0.275042 -0.275042)
							(end 0.3048 -0.2032)
						)
					)
					(width 0)
					(fill yes)
				)
			)
		)
		(pad "2" smd custom
			(at 0 0.4445 90)
			(size 0.1524 0.1524)
			(layers "B.Cu" "B.Mask" "B.Paste")
			(net "GND")
			(options
				(clearance outline)
				(anchor circle)
			)
			(primitives
				(gr_poly
					(pts
						(arc
							(start 0.3048 0.2032)
							(mid 0.275042 0.275042)
							(end 0.2032 0.3048)
						)
						(arc
							(start -0.2032 0.3048)
							(mid -0.275042 0.275042)
							(end -0.3048 0.2032)
						)
						(arc
							(start -0.3048 -0.2032)
							(mid -0.275042 -0.275042)
							(end -0.2032 -0.3048)
						)
						(arc
							(start 0.2032 -0.3048)
							(mid 0.275042 -0.275042)
							(end 0.3048 -0.2032)
						)
					)
					(width 0)
					(fill yes)
				)
			)
		)
	)
	(footprint ""
		(layer "B.Cu")
		(at 327.025 -109.982 90)
		(property "Reference" "PC27"
			(at 0 0 90)
			(layer "B.SilkS")
			(hide yes)
			(effects
				(font
					(size 1.27 1.27)
				)
				(justify mirror)
			)
		)
		(property "Value" "SCD1U50V3KX-GP"
			(at 0 -2.8194 90)
			(unlocked yes)
			(layer "B.Fab")
			(hide yes)
			(effects
				(font
					(size 1.016 1.016)
					(thickness 0.1524)
				)
				(justify mirror)
			)
		)
		(property "Device Type" "C603H36"
			(at 0 -4.3434 90)
			(unlocked yes)
			(layer "B.Fab")
			(hide yes)
			(effects
				(font
					(size 1.016 1.016)
					(thickness 0.1524)
				)
				(justify mirror)
			)
		)
		(duplicate_pad_numbers_are_jumpers no)
		(fp_line
			(start -0.508 0)
			(end 0.508 0)
			(stroke
				(width 0.2032)
				(type default)
			)
			(layer "B.SilkS")
		)
		(fp_rect
			(start 0.5842 1.3335)
			(end -0.5842 -1.3335)
			(stroke
				(width 0)
				(type default)
			)
			(fill no)
			(layer "B.CrtYd")
		)
		(fp_rect
			(start 0.5842 1.3335)
			(end -0.5842 -1.3335)
			(stroke
				(width 0)
				(type default)
			)
			(fill no)
			(layer "B.Fab")
		)
		(pad "1" smd custom
			(at 0 -0.762 270)
			(size 0.2159 0.2159)
			(layers "B.Cu" "B.Mask" "B.Paste")
			(net "P3V3_STBY_VBST_RC")
			(options
				(clearance outline)
				(anchor circle)
			)
			(primitives
				(gr_poly
					(pts
						(arc
							(start -0.3302 0.4318)
							(mid -0.402042 0.402042)
							(end -0.4318 0.3302)
						)
						(arc
							(start -0.4318 -0.3302)
							(mid -0.402042 -0.402042)
							(end -0.3302 -0.4318)
						)
						(arc
							(start 0.3302 -0.4318)
							(mid 0.402042 -0.402042)
							(end 0.4318 -0.3302)
						)
						(arc
							(start 0.4318 0.3302)
							(mid 0.402042 0.402042)
							(end 0.3302 0.4318)
						)
					)
					(width 0)
					(fill yes)
				)
			)
		)
		(pad "2" smd custom
			(at 0 0.762 270)
			(size 0.2159 0.2159)
			(layers "B.Cu" "B.Mask" "B.Paste")
			(net "P3V3_STBY_LL")
			(options
				(clearance outline)
				(anchor circle)
			)
			(primitives
				(gr_poly
					(pts
						(arc
							(start -0.3302 0.4318)
							(mid -0.402042 0.402042)
							(end -0.4318 0.3302)
						)
						(arc
							(start -0.4318 -0.3302)
							(mid -0.402042 -0.402042)
							(end -0.3302 -0.4318)
						)
						(arc
							(start 0.3302 -0.4318)
							(mid 0.402042 -0.402042)
							(end 0.4318 -0.3302)
						)
						(arc
							(start 0.4318 0.3302)
							(mid 0.402042 0.402042)
							(end 0.3302 0.4318)
						)
					)
					(width 0)
					(fill yes)
				)
			)
		)
	)
	(footprint ""
		(layer "B.Cu")
		(at 96.339406 -41.81602 90)
		(property "Reference" "SC962"
			(at 0 0 90)
			(layer "B.SilkS")
			(hide yes)
			(effects
				(font
					(size 1.27 1.27)
				)
				(justify mirror)
			)
		)
		(property "Value" "SCD1U6D3V1KX-GP"
			(at 2.8321 -1.7399 90)
			(unlocked yes)
			(layer "B.Fab")
			(hide yes)
			(effects
				(font
					(size 1.016 1.016)
					(thickness 0.1524)
				)
				(justify mirror)
			)
		)
		(property "Device Type" "C0201H13"
			(at 2.8321 -3.2639 90)
			(unlocked yes)
			(layer "B.Fab")
			(hide yes)
			(effects
				(font
					(size 1.016 1.016)
					(thickness 0.1524)
				)
				(justify mirror)
			)
		)
		(duplicate_pad_numbers_are_jumpers no)
		(fp_rect
			(start 0.2794 0.6477)
			(end -0.2794 -0.6477)
			(stroke
				(width 0)
				(type default)
			)
			(fill no)
			(layer "B.CrtYd")
		)
		(fp_rect
			(start 0.2794 0.6477)
			(end -0.2794 -0.6477)
			(stroke
				(width 0)
				(type default)
			)
			(fill no)
			(layer "B.Fab")
		)
		(pad "1" smd custom
			(at 0 -0.2794 270)
			(size 0.0762 0.0762)
			(layers "B.Cu" "B.Mask" "B.Paste")
			(net "SAS0_AVDD")
			(options
				(clearance outline)
				(anchor circle)
			)
			(primitives
				(gr_poly
					(pts
						(arc
							(start 0.1524 0.127)
							(mid 0.137521 0.162921)
							(end 0.1016 0.1778)
						)
						(arc
							(start -0.1016 0.1778)
							(mid -0.137521 0.162921)
							(end -0.1524 0.127)
						)
						(arc
							(start -0.1524 -0.127)
							(mid -0.137521 -0.162921)
							(end -0.1016 -0.1778)
						)
						(arc
							(start 0.1016 -0.1778)
							(mid 0.137521 -0.162921)
							(end 0.1524 -0.127)
						)
					)
					(width 0)
					(fill yes)
				)
			)
		)
		(pad "2" smd custom
			(at 0 0.2794 270)
			(size 0.0762 0.0762)
			(layers "B.Cu" "B.Mask" "B.Paste")
			(net "GND")
			(options
				(clearance outline)
				(anchor circle)
			)
			(primitives
				(gr_poly
					(pts
						(arc
							(start 0.1524 0.127)
							(mid 0.137521 0.162921)
							(end 0.1016 0.1778)
						)
						(arc
							(start -0.1016 0.1778)
							(mid -0.137521 0.162921)
							(end -0.1524 0.127)
						)
						(arc
							(start -0.1524 -0.127)
							(mid -0.137521 -0.162921)
							(end -0.1016 -0.1778)
						)
						(arc
							(start 0.1016 -0.1778)
							(mid 0.137521 -0.162921)
							(end 0.1524 -0.127)
						)
					)
					(width 0)
					(fill yes)
				)
			)
		)
	)
)
